(kicad_pcb
	(version 20260206)
	(generator "pcbnew")
	(generator_version "10.0")
	(general
		(thickness 1.6)
		(legacy_teardrops no)
	)
	(paper "A4")
	(title_block
		(title "ptb — 12523-1.1018WZS1506.brd")
		(comment 1 "Open Vault / Knox (Wiwynn) / footprints 35-41 of 61")
	)
	(layers
		(0 "F.Cu" signal "TOP")
		(4 "In1.Cu" signal "L2GND")
		(6 "In2.Cu" signal "L3VCC")
		(2 "B.Cu" signal "BOTTOM")
		(9 "F.Adhes" user "F.Adhesive")
		(11 "B.Adhes" user "B.Adhesive")
		(13 "F.Paste" user "Package Geometry/Pastemask Top")
		(15 "B.Paste" user "Package Geometry/Pastemask Bottom")
		(5 "F.SilkS" user "Ref Des/Silkscreen Top")
		(7 "B.SilkS" user "Ref Des/Silkscreen Bottom")
		(1 "F.Mask" user "Board Geometry/Soldermask Top")
		(3 "B.Mask" user "Board Geometry/Soldermask Bottom")
		(17 "Dwgs.User" user "User.Drawings")
		(19 "Cmts.User" user "User.Comments")
		(21 "Eco1.User" user "User.Eco1")
		(23 "Eco2.User" user "User.Eco2")
		(25 "Edge.Cuts" user "Board Geometry/Outline")
		(27 "Margin" user)
		(31 "F.CrtYd" user "Package Geometry/Place Bound Top")
		(29 "B.CrtYd" user "Package Geometry/Place Bound Bottom")
		(35 "F.Fab" user "Ref Des/Assembly Top")
		(33 "B.Fab" user "Ref Des/Assembly Bottom")
	)
	(footprint ""
		(layer "F.Cu")
		(at 10.940288 -93.356938)
		(property "Reference" "R484"
			(at 0 0 0)
			(layer "F.SilkS")
			(hide yes)
			(effects
				(font
					(size 1.27 1.27)
				)
			)
		)
		(property "Value" "0R2J-2-GP"
			(at 0.064008 -3.993896 0)
			(unlocked yes)
			(layer "F.Fab")
			(hide yes)
			(effects
				(font
					(size 1.016 1.016)
					(thickness 0.1524)
				)
			)
		)
		(property "Device Type" "R402H16"
			(at 0.064008 -5.517896 0)
			(unlocked yes)
			(layer "F.Fab")
			(hide yes)
			(effects
				(font
					(size 1.016 1.016)
					(thickness 0.1524)
				)
			)
		)
		(duplicate_pad_numbers_are_jumpers no)
		(fp_line
			(start -0.508 -0.9398)
			(end -0.508 0.9398)
			(stroke
				(width 0.1524)
				(type default)
			)
			(layer "F.SilkS")
		)
		(fp_line
			(start 0.508 -0.9398)
			(end -0.508 -0.9398)
			(stroke
				(width 0.1524)
				(type default)
			)
			(layer "F.SilkS")
		)
		(fp_rect
			(start -0.508 0.9398)
			(end 0.508 -0.9398)
			(stroke
				(width 0)
				(type default)
			)
			(fill no)
			(layer "F.CrtYd")
		)
		(fp_rect
			(start -0.508 0.9398)
			(end 0.508 -0.9398)
			(stroke
				(width 0)
				(type default)
			)
			(fill no)
			(layer "F.Fab")
		)
		(pad "1" smd custom
			(at 0 -0.4445)
			(size 0.1397 0.1397)
			(layers "F.Cu" "F.Mask" "F.Paste")
			(net "I2C_C_SCL")
			(options
				(clearance outline)
				(anchor circle)
			)
			(primitives
				(gr_poly
					(pts
						(arc
							(start -0.1778 -0.2794)
							(mid -0.249642 -0.249642)
							(end -0.2794 -0.1778)
						)
						(arc
							(start -0.2794 0.1778)
							(mid -0.249642 0.249642)
							(end -0.1778 0.2794)
						)
						(arc
							(start 0.1778 0.2794)
							(mid 0.249642 0.249642)
							(end 0.2794 0.1778)
						)
						(arc
							(start 0.2794 -0.1778)
							(mid 0.249642 -0.249642)
							(end 0.1778 -0.2794)
						)
					)
					(width 0)
					(fill yes)
				)
			)
		)
		(pad "2" smd custom
			(at 0 0.4445)
			(size 0.1397 0.1397)
			(layers "F.Cu" "F.Mask" "F.Paste")
			(net "I2C_C_BUF_SCLOUT")
			(options
				(clearance outline)
				(anchor circle)
			)
			(primitives
				(gr_poly
					(pts
						(arc
							(start -0.1778 -0.2794)
							(mid -0.249642 -0.249642)
							(end -0.2794 -0.1778)
						)
						(arc
							(start -0.2794 0.1778)
							(mid -0.249642 0.249642)
							(end -0.1778 0.2794)
						)
						(arc
							(start 0.1778 0.2794)
							(mid 0.249642 0.249642)
							(end 0.2794 0.1778)
						)
						(arc
							(start 0.2794 -0.1778)
							(mid 0.249642 -0.249642)
							(end 0.1778 -0.2794)
						)
					)
					(width 0)
					(fill yes)
				)
			)
		)
	)
	(footprint ""
		(layer "F.Cu")
		(at 155.66009 -98.799904 90)
		(property "Reference" "Q31"
			(at 0 0 90)
			(layer "F.SilkS")
			(hide yes)
			(effects
				(font
					(size 1.27 1.27)
				)
			)
		)
		(property "Value" "SENSOR-2P-GP-U"
			(at -3.4036 1.3462 90)
			(unlocked yes)
			(layer "F.Fab")
			(hide yes)
			(effects
				(font
					(size 1.016 1.016)
					(thickness 0.1524)
				)
			)
		)
		(property "Device Type" "SNR2N4036-UH166"
			(at -3.4036 -0.1778 90)
			(unlocked yes)
			(layer "F.Fab")
			(hide yes)
			(effects
				(font
					(size 1.016 1.016)
					(thickness 0.1524)
				)
			)
		)
		(duplicate_pad_numbers_are_jumpers no)
		(fp_line
			(start 2.0574 -2.6543)
			(end -2.1844 -2.6543)
			(stroke
				(width 0.1524)
				(type default)
			)
			(layer "F.SilkS")
		)
		(fp_line
			(start -2.1844 -2.6543)
			(end -2.1844 2.6543)
			(stroke
				(width 0.1524)
				(type default)
			)
			(layer "F.SilkS")
		)
		(fp_line
			(start 2.0574 2.6543)
			(end 2.0574 -2.6543)
			(stroke
				(width 0.1524)
				(type default)
			)
			(layer "F.SilkS")
		)
		(fp_line
			(start -2.1844 2.6543)
			(end 2.0574 2.6543)
			(stroke
				(width 0.1524)
				(type default)
			)
			(layer "F.SilkS")
		)
		(fp_poly
			(pts
				(xy -1.0668 3.4036) (xy -1.0668 2.7178) (xy -1.7272 2.7178) (xy -1.7272 3.4036)
			)
			(stroke
				(width 0)
				(type default)
			)
			(fill yes)
			(layer "F.SilkS")
		)
		(fp_rect
			(start -1.8034 1.9939)
			(end 1.8034 -1.9939)
			(stroke
				(width 0)
				(type default)
			)
			(fill no)
			(layer "F.CrtYd")
		)
		(fp_poly
			(pts
				(xy -2.4384 2.7305) (xy -2.4384 -2.7305) (xy 2.3114 -2.7305) (xy 2.3114 1.98882) (xy 1.8034 1.98882)
				(xy 1.8034 -1.9939) (xy -1.8034 -1.9939) (xy -1.8034 1.9939) (xy 2.3114 1.9939) (xy 2.3114 2.7305)
			)
			(stroke
				(width 0)
				(type default)
			)
			(fill no)
			(layer "F.CrtYd")
		)
		(fp_rect
			(start -2.4384 2.7305)
			(end 2.3114 -2.7305)
			(stroke
				(width 0)
				(type default)
			)
			(fill no)
			(layer "F.Fab")
		)
		(fp_text user "E"
			(at 2.038096 -3.71729 90)
			(unlocked yes)
			(layer "F.SilkS")
			(effects
				(font
					(size 1.016 1.016)
					(thickness 0.1524)
				)
			)
		)
		(fp_text user "C"
			(at 2.038096 3.64871 90)
			(unlocked yes)
			(layer "F.SilkS")
			(effects
				(font
					(size 1.016 1.016)
					(thickness 0.1524)
				)
			)
		)
		(pad "C" smd rect
			(at -0.374904 1.455674 90)
			(size 3.0988 1.8796)
			(layers "F.Cu" "F.Mask" "F.Paste")
			(net "DETECTOR_C")
		)
		(pad "E" smd rect
			(at -0.374904 -1.455674 90)
			(size 3.0988 1.8796)
			(layers "F.Cu" "F.Mask" "F.Paste")
			(net "IR_SWITCH_E")
		)
	)
	(footprint ""
		(layer "F.Cu")
		(at 136.652 -74.93)
		(property "Reference" "R379"
			(at 0 0 0)
			(layer "F.SilkS")
			(hide yes)
			(effects
				(font
					(size 1.27 1.27)
				)
			)
		)
		(property "Value" "10KR2F-2-GP"
			(at 0.064008 -3.993896 0)
			(unlocked yes)
			(layer "F.Fab")
			(hide yes)
			(effects
				(font
					(size 1.016 1.016)
					(thickness 0.1524)
				)
			)
		)
		(property "Device Type" "R402H16"
			(at 0.064008 -5.517896 0)
			(unlocked yes)
			(layer "F.Fab")
			(hide yes)
			(effects
				(font
					(size 1.016 1.016)
					(thickness 0.1524)
				)
			)
		)
		(duplicate_pad_numbers_are_jumpers no)
		(fp_line
			(start -0.508 -0.9398)
			(end -0.508 0.9398)
			(stroke
				(width 0.1524)
				(type default)
			)
			(layer "F.SilkS")
		)
		(fp_line
			(start 0.508 -0.9398)
			(end -0.508 -0.9398)
			(stroke
				(width 0.1524)
				(type default)
			)
			(layer "F.SilkS")
		)
		(fp_rect
			(start -0.508 0.9398)
			(end 0.508 -0.9398)
			(stroke
				(width 0)
				(type default)
			)
			(fill no)
			(layer "F.CrtYd")
		)
		(fp_rect
			(start -0.508 0.9398)
			(end 0.508 -0.9398)
			(stroke
				(width 0)
				(type default)
			)
			(fill no)
			(layer "F.Fab")
		)
		(pad "1" smd custom
			(at 0 -0.4445)
			(size 0.1397 0.1397)
			(layers "F.Cu" "F.Mask" "F.Paste")
			(net "P3V3")
			(options
				(clearance outline)
				(anchor circle)
			)
			(primitives
				(gr_poly
					(pts
						(arc
							(start -0.1778 -0.2794)
							(mid -0.249642 -0.249642)
							(end -0.2794 -0.1778)
						)
						(arc
							(start -0.2794 0.1778)
							(mid -0.249642 0.249642)
							(end -0.1778 0.2794)
						)
						(arc
							(start 0.1778 0.2794)
							(mid 0.249642 0.249642)
							(end 0.2794 0.1778)
						)
						(arc
							(start 0.2794 -0.1778)
							(mid 0.249642 -0.249642)
							(end 0.1778 -0.2794)
						)
					)
					(width 0)
					(fill yes)
				)
			)
		)
		(pad "2" smd custom
			(at 0 0.4445)
			(size 0.1397 0.1397)
			(layers "F.Cu" "F.Mask" "F.Paste")
			(net "SELF_TRAY_PRESENT")
			(options
				(clearance outline)
				(anchor circle)
			)
			(primitives
				(gr_poly
					(pts
						(arc
							(start -0.1778 -0.2794)
							(mid -0.249642 -0.249642)
							(end -0.2794 -0.1778)
						)
						(arc
							(start -0.2794 0.1778)
							(mid -0.249642 0.249642)
							(end -0.1778 0.2794)
						)
						(arc
							(start 0.1778 0.2794)
							(mid 0.249642 0.249642)
							(end 0.2794 0.1778)
						)
						(arc
							(start 0.2794 -0.1778)
							(mid 0.249642 -0.249642)
							(end 0.1778 -0.2794)
						)
					)
					(width 0)
					(fill yes)
				)
			)
		)
	)
	(footprint ""
		(layer "F.Cu")
		(at 8.079232 -95.029528 90)
		(property "Reference" "R388"
			(at 0 0 90)
			(layer "F.SilkS")
			(hide yes)
			(effects
				(font
					(size 1.27 1.27)
				)
			)
		)
		(property "Value" "0R2J-2-GP"
			(at 0.064008 -3.993896 90)
			(unlocked yes)
			(layer "F.Fab")
			(hide yes)
			(effects
				(font
					(size 1.016 1.016)
					(thickness 0.1524)
				)
			)
		)
		(property "Device Type" "R402H16"
			(at 0.064008 -5.517896 90)
			(unlocked yes)
			(layer "F.Fab")
			(hide yes)
			(effects
				(font
					(size 1.016 1.016)
					(thickness 0.1524)
				)
			)
		)
		(duplicate_pad_numbers_are_jumpers no)
		(fp_line
			(start 0.508 -0.9398)
			(end -0.508 -0.9398)
			(stroke
				(width 0.1524)
				(type default)
			)
			(layer "F.SilkS")
		)
		(fp_line
			(start -0.508 -0.9398)
			(end -0.508 0.9398)
			(stroke
				(width 0.1524)
				(type default)
			)
			(layer "F.SilkS")
		)
		(fp_rect
			(start -0.508 0.9398)
			(end 0.508 -0.9398)
			(stroke
				(width 0)
				(type default)
			)
			(fill no)
			(layer "F.CrtYd")
		)
		(fp_rect
			(start -0.508 0.9398)
			(end 0.508 -0.9398)
			(stroke
				(width 0)
				(type default)
			)
			(fill no)
			(layer "F.Fab")
		)
		(pad "1" smd custom
			(at 0 -0.4445 90)
			(size 0.1397 0.1397)
			(layers "F.Cu" "F.Mask" "F.Paste")
			(net "STRADDLE_I2C_C_SDA")
			(options
				(clearance outline)
				(anchor circle)
			)
			(primitives
				(gr_poly
					(pts
						(arc
							(start -0.1778 -0.2794)
							(mid -0.249642 -0.249642)
							(end -0.2794 -0.1778)
						)
						(arc
							(start -0.2794 0.1778)
							(mid -0.249642 0.249642)
							(end -0.1778 0.2794)
						)
						(arc
							(start 0.1778 0.2794)
							(mid 0.249642 0.249642)
							(end 0.2794 0.1778)
						)
						(arc
							(start 0.2794 -0.1778)
							(mid 0.249642 -0.249642)
							(end 0.1778 -0.2794)
						)
					)
					(width 0)
					(fill yes)
				)
			)
		)
		(pad "2" smd custom
			(at 0 0.4445 90)
			(size 0.1397 0.1397)
			(layers "F.Cu" "F.Mask" "F.Paste")
			(net "I2C_C_SDA")
			(options
				(clearance outline)
				(anchor circle)
			)
			(primitives
				(gr_poly
					(pts
						(arc
							(start -0.1778 -0.2794)
							(mid -0.249642 -0.249642)
							(end -0.2794 -0.1778)
						)
						(arc
							(start -0.2794 0.1778)
							(mid -0.249642 0.249642)
							(end -0.1778 0.2794)
						)
						(arc
							(start 0.1778 0.2794)
							(mid 0.249642 0.249642)
							(end 0.2794 0.1778)
						)
						(arc
							(start 0.2794 -0.1778)
							(mid 0.249642 -0.249642)
							(end 0.1778 -0.2794)
						)
					)
					(width 0)
					(fill yes)
				)
			)
		)
	)
	(footprint ""
		(layer "F.Cu")
		(at 17.220692 -93.84538 90)
		(property "Reference" "R480"
			(at 0 0 90)
			(layer "F.SilkS")
			(hide yes)
			(effects
				(font
					(size 1.27 1.27)
				)
			)
		)
		(property "Value" "0R2J-2-GP"
			(at 0.064008 -3.993896 90)
			(unlocked yes)
			(layer "F.Fab")
			(hide yes)
			(effects
				(font
					(size 1.016 1.016)
					(thickness 0.1524)
				)
			)
		)
		(property "Device Type" "R402H16"
			(at 0.064008 -5.517896 90)
			(unlocked yes)
			(layer "F.Fab")
			(hide yes)
			(effects
				(font
					(size 1.016 1.016)
					(thickness 0.1524)
				)
			)
		)
		(duplicate_pad_numbers_are_jumpers no)
		(fp_line
			(start 0.508 -0.9398)
			(end -0.508 -0.9398)
			(stroke
				(width 0.1524)
				(type default)
			)
			(layer "F.SilkS")
		)
		(fp_line
			(start -0.508 -0.9398)
			(end -0.508 0.9398)
			(stroke
				(width 0.1524)
				(type default)
			)
			(layer "F.SilkS")
		)
		(fp_rect
			(start -0.508 0.9398)
			(end 0.508 -0.9398)
			(stroke
				(width 0)
				(type default)
			)
			(fill no)
			(layer "F.CrtYd")
		)
		(fp_rect
			(start -0.508 0.9398)
			(end 0.508 -0.9398)
			(stroke
				(width 0)
				(type default)
			)
			(fill no)
			(layer "F.Fab")
		)
		(pad "1" smd custom
			(at 0 -0.4445 90)
			(size 0.1397 0.1397)
			(layers "F.Cu" "F.Mask" "F.Paste")
			(net "I2C_C_SCL")
			(options
				(clearance outline)
				(anchor circle)
			)
			(primitives
				(gr_poly
					(pts
						(arc
							(start -0.1778 -0.2794)
							(mid -0.249642 -0.249642)
							(end -0.2794 -0.1778)
						)
						(arc
							(start -0.2794 0.1778)
							(mid -0.249642 0.249642)
							(end -0.1778 0.2794)
						)
						(arc
							(start 0.1778 0.2794)
							(mid 0.249642 0.249642)
							(end 0.2794 0.1778)
						)
						(arc
							(start 0.2794 -0.1778)
							(mid 0.249642 -0.249642)
							(end 0.1778 -0.2794)
						)
					)
					(width 0)
					(fill yes)
				)
			)
		)
		(pad "2" smd custom
			(at 0 0.4445 90)
			(size 0.1397 0.1397)
			(layers "F.Cu" "F.Mask" "F.Paste")
			(net "I2C_C_BUF_SCL")
			(options
				(clearance outline)
				(anchor circle)
			)
			(primitives
				(gr_poly
					(pts
						(arc
							(start -0.1778 -0.2794)
							(mid -0.249642 -0.249642)
							(end -0.2794 -0.1778)
						)
						(arc
							(start -0.2794 0.1778)
							(mid -0.249642 0.249642)
							(end -0.1778 0.2794)
						)
						(arc
							(start 0.1778 0.2794)
							(mid 0.249642 0.249642)
							(end 0.2794 0.1778)
						)
						(arc
							(start 0.2794 -0.1778)
							(mid 0.249642 -0.249642)
							(end 0.1778 -0.2794)
						)
					)
					(width 0)
					(fill yes)
				)
			)
		)
	)
	(footprint ""
		(layer "F.Cu")
		(at 13.38707 -89.94013 180)
		(property "Reference" "R342"
			(at 0 0 180)
			(layer "F.SilkS")
			(hide yes)
			(effects
				(font
					(size 1.27 1.27)
				)
			)
		)
		(property "Value" "10KR2F-2-GP"
			(at 0.064008 -3.993896 180)
			(unlocked yes)
			(layer "F.Fab")
			(hide yes)
			(effects
				(font
					(size 1.016 1.016)
					(thickness 0.1524)
				)
			)
		)
		(property "Device Type" "R402H16"
			(at 0.064008 -5.517896 180)
			(unlocked yes)
			(layer "F.Fab")
			(hide yes)
			(effects
				(font
					(size 1.016 1.016)
					(thickness 0.1524)
				)
			)
		)
		(duplicate_pad_numbers_are_jumpers no)
		(fp_line
			(start 0.508 -0.9398)
			(end -0.508 -0.9398)
			(stroke
				(width 0.1524)
				(type default)
			)
			(layer "F.SilkS")
		)
		(fp_line
			(start -0.508 -0.9398)
			(end -0.508 0.9398)
			(stroke
				(width 0.1524)
				(type default)
			)
			(layer "F.SilkS")
		)
		(fp_rect
			(start -0.508 0.9398)
			(end 0.508 -0.9398)
			(stroke
				(width 0)
				(type default)
			)
			(fill no)
			(layer "F.CrtYd")
		)
		(fp_rect
			(start -0.508 0.9398)
			(end 0.508 -0.9398)
			(stroke
				(width 0)
				(type default)
			)
			(fill no)
			(layer "F.Fab")
		)
		(pad "1" smd custom
			(at 0 -0.4445 180)
			(size 0.1397 0.1397)
			(layers "F.Cu" "F.Mask" "F.Paste")
			(net "P3V3")
			(options
				(clearance outline)
				(anchor circle)
			)
			(primitives
				(gr_poly
					(pts
						(arc
							(start -0.1778 -0.2794)
							(mid -0.249642 -0.249642)
							(end -0.2794 -0.1778)
						)
						(arc
							(start -0.2794 0.1778)
							(mid -0.249642 0.249642)
							(end -0.1778 0.2794)
						)
						(arc
							(start 0.1778 0.2794)
							(mid 0.249642 0.249642)
							(end 0.2794 0.1778)
						)
						(arc
							(start 0.2794 -0.1778)
							(mid 0.249642 -0.249642)
							(end 0.1778 -0.2794)
						)
					)
					(width 0)
					(fill yes)
				)
			)
		)
		(pad "2" smd custom
			(at 0 0.4445 180)
			(size 0.1397 0.1397)
			(layers "F.Cu" "F.Mask" "F.Paste")
			(net "I2C_C_BUF_SCLOUT")
			(options
				(clearance outline)
				(anchor circle)
			)
			(primitives
				(gr_poly
					(pts
						(arc
							(start -0.1778 -0.2794)
							(mid -0.249642 -0.249642)
							(end -0.2794 -0.1778)
						)
						(arc
							(start -0.2794 0.1778)
							(mid -0.249642 0.249642)
							(end -0.1778 0.2794)
						)
						(arc
							(start 0.1778 0.2794)
							(mid 0.249642 0.249642)
							(end 0.2794 0.1778)
						)
						(arc
							(start 0.2794 -0.1778)
							(mid 0.249642 -0.249642)
							(end 0.1778 -0.2794)
						)
					)
					(width 0)
					(fill yes)
				)
			)
		)
	)
	(footprint ""
		(layer "F.Cu")
		(at 135.086344 -83.972908 90)
		(property "Reference" "R365"
			(at 0 0 90)
			(layer "F.SilkS")
			(hide yes)
			(effects
				(font
					(size 1.27 1.27)
				)
			)
		)
		(property "Value" "0R2J-2-GP"
			(at 0.064008 -3.993896 90)
			(unlocked yes)
			(layer "F.Fab")
			(hide yes)
			(effects
				(font
					(size 1.016 1.016)
					(thickness 0.1524)
				)
			)
		)
		(property "Device Type" "R402H16"
			(at 0.064008 -5.517896 90)
			(unlocked yes)
			(layer "F.Fab")
			(hide yes)
			(effects
				(font
					(size 1.016 1.016)
					(thickness 0.1524)
				)
			)
		)
		(duplicate_pad_numbers_are_jumpers no)
		(fp_line
			(start 0.508 -0.9398)
			(end -0.508 -0.9398)
			(stroke
				(width 0.1524)
				(type default)
			)
			(layer "F.SilkS")
		)
		(fp_line
			(start -0.508 -0.9398)
			(end -0.508 0.9398)
			(stroke
				(width 0.1524)
				(type default)
			)
			(layer "F.SilkS")
		)
		(fp_rect
			(start -0.508 0.9398)
			(end 0.508 -0.9398)
			(stroke
				(width 0)
				(type default)
			)
			(fill no)
			(layer "F.CrtYd")
		)
		(fp_rect
			(start -0.508 0.9398)
			(end 0.508 -0.9398)
			(stroke
				(width 0)
				(type default)
			)
			(fill no)
			(layer "F.Fab")
		)
		(pad "1" smd custom
			(at 0 -0.4445 90)
			(size 0.1397 0.1397)
			(layers "F.Cu" "F.Mask" "F.Paste")
			(net "TRAY PRESENT_OUT_NET")
			(options
				(clearance outline)
				(anchor circle)
			)
			(primitives
				(gr_poly
					(pts
						(arc
							(start -0.1778 -0.2794)
							(mid -0.249642 -0.249642)
							(end -0.2794 -0.1778)
						)
						(arc
							(start -0.2794 0.1778)
							(mid -0.249642 0.249642)
							(end -0.1778 0.2794)
						)
						(arc
							(start 0.1778 0.2794)
							(mid 0.249642 0.249642)
							(end 0.2794 0.1778)
						)
						(arc
							(start 0.2794 -0.1778)
							(mid 0.249642 -0.249642)
							(end 0.1778 -0.2794)
						)
					)
					(width 0)
					(fill yes)
				)
			)
		)
		(pad "2" smd custom
			(at 0 0.4445 90)
			(size 0.1397 0.1397)
			(layers "F.Cu" "F.Mask" "F.Paste")
			(net "TRAY_MOSFET_G")
			(options
				(clearance outline)
				(anchor circle)
			)
			(primitives
				(gr_poly
					(pts
						(arc
							(start -0.1778 -0.2794)
							(mid -0.249642 -0.249642)
							(end -0.2794 -0.1778)
						)
						(arc
							(start -0.2794 0.1778)
							(mid -0.249642 0.249642)
							(end -0.1778 0.2794)
						)
						(arc
							(start 0.1778 0.2794)
							(mid 0.249642 0.249642)
							(end 0.2794 0.1778)
						)
						(arc
							(start 0.2794 -0.1778)
							(mid 0.249642 -0.249642)
							(end 0.1778 -0.2794)
						)
					)
					(width 0)
					(fill yes)
				)
			)
		)
	)
)
